# T6G (Grand Teton) — schematic netlist excerpt (pin names and nets, part order shuffled) for the footprints in the layout excerpt that follows; sources: Cadence DE-HDL packaged netlist, KiCad conversion of 04192023_DAF0TMB3IC0_F0TG_MB_C_brd_V02_OCP.brd

PR6003  Q_RES  10K 1% CHIP  pkg 0402LF  page 269 : A = P1V8_AUX_CS ; B = GND
R1093  Q_RES  0 5% EMPTY  pkg 0402LF  page 312 : A = P1V8_CPU0_RT_1D ; B = P1V8_CPU0_RT3_1A_1D

(kicad_pcb
	(version 20260206)
	(generator "pcbnew")
	(generator_version "10.0")
	(general
		(thickness 1.6)
		(legacy_teardrops no)
	)
	(paper "A4")
	(title_block
		(title "04192023_DAF0TMB3IC0_F0TG_MB_C_brd_V02_OCP.brd")
		(comment 1 "Grand Teton / footprints 979-980 of 8354")
	)
	(layers
		(0 "F.Cu" signal "TOP")
		(4 "In1.Cu" signal "GND")
		(6 "In2.Cu" signal "IN1")
		(8 "In3.Cu" signal "GND1")
		(10 "In4.Cu" signal "IN2")
		(12 "In5.Cu" signal "GND2")
		(14 "In6.Cu" signal "IN3")
		(16 "In7.Cu" signal "GND3")
		(18 "In8.Cu" signal "VCC")
		(20 "In9.Cu" signal "VCC1")
		(22 "In10.Cu" signal "GND4")
		(24 "In11.Cu" signal "IN4")
		(26 "In12.Cu" signal "GND5")
		(28 "In13.Cu" signal "IN5")
		(30 "In14.Cu" signal "GND6")
		(32 "In15.Cu" signal "IN6")
		(34 "In16.Cu" signal "GND7")
		(2 "B.Cu" signal "BOTTOM")
		(9 "F.Adhes" user "F.Adhesive")
		(11 "B.Adhes" user "B.Adhesive")
		(13 "F.Paste" user "Package Geometry/Pastemask Top")
		(15 "B.Paste" user "Package Geometry/Pastemask Bottom")
		(5 "F.SilkS" user "Ref Des/Silkscreen Top")
		(7 "B.SilkS" user "Ref Des/Silkscreen Bottom")
		(1 "F.Mask" user "Board Geometry/Soldermask Top")
		(3 "B.Mask" user "Board Geometry/Soldermask Bottom")
		(17 "Dwgs.User" user "User.Drawings")
		(19 "Cmts.User" user "User.Comments")
		(21 "Eco1.User" user "User.Eco1")
		(23 "Eco2.User" user "User.Eco2")
		(25 "Edge.Cuts" user "Board Geometry/Outline")
		(27 "Margin" user)
		(31 "F.CrtYd" user "Package Geometry/Place Bound Top")
		(29 "B.CrtYd" user "Package Geometry/Place Bound Bottom")
		(35 "F.Fab" user "Ref Des/Assembly Top")
		(33 "B.Fab" user "Ref Des/Assembly Bottom")
	)
	(footprint ""
		(layer "F.Cu")
		(at 393.762484 -392.48588 180)
		(property "Reference" "R1093"
			(at 0 0 180)
			(layer "F.SilkS")
			(hide yes)
			(effects
				(font
					(size 1.27 1.27)
				)
			)
		)
		(property "Value" ""
			(at 0 0 180)
			(layer "F.Fab")
			(effects
				(font
					(size 1.27 1.27)
				)
			)
		)
		(duplicate_pad_numbers_are_jumpers no)
		(fp_line
			(start 0.7874 0.4064)
			(end -0.7874 0.4064)
			(stroke
				(width 0.1524)
				(type default)
			)
			(layer "F.SilkS")
		)
		(fp_line
			(start 0.7874 -0.4064)
			(end 0.7874 0.4064)
			(stroke
				(width 0.1524)
				(type default)
			)
			(layer "F.SilkS")
		)
		(fp_line
			(start -0.7874 0.4064)
			(end -0.7874 -0.4064)
			(stroke
				(width 0.1524)
				(type default)
			)
			(layer "F.SilkS")
		)
		(fp_line
			(start -0.7874 -0.4064)
			(end 0.7874 -0.4064)
			(stroke
				(width 0.1524)
				(type default)
			)
			(layer "F.SilkS")
		)
		(fp_line
			(start 0.67945 0.3048)
			(end 0.120396 0.3048)
			(stroke
				(width 0.1)
				(type default)
			)
			(layer "F.Fab")
		)
		(fp_line
			(start 0.67945 -0.3048)
			(end 0.67945 0.3048)
			(stroke
				(width 0.1)
				(type default)
			)
			(layer "F.Fab")
		)
		(fp_line
			(start 0.12065 -0.2794)
			(end 0.12065 -0.3048)
			(stroke
				(width 0.1)
				(type default)
			)
			(layer "F.Fab")
		)
		(fp_line
			(start 0.12065 -0.3048)
			(end 0.67945 -0.3048)
			(stroke
				(width 0.1)
				(type default)
			)
			(layer "F.Fab")
		)
		(fp_line
			(start 0.120396 0.3048)
			(end 0.120396 0.2794)
			(stroke
				(width 0.1)
				(type default)
			)
			(layer "F.Fab")
		)
		(fp_line
			(start 0.120396 0.2794)
			(end -0.12065 0.2794)
			(stroke
				(width 0.1)
				(type default)
			)
			(layer "F.Fab")
		)
		(fp_line
			(start -0.12065 0.3048)
			(end -0.67945 0.3048)
			(stroke
				(width 0.1)
				(type default)
			)
			(layer "F.Fab")
		)
		(fp_line
			(start -0.12065 0.2794)
			(end -0.12065 0.3048)
			(stroke
				(width 0.1)
				(type default)
			)
			(layer "F.Fab")
		)
		(fp_line
			(start -0.12065 -0.2794)
			(end 0.12065 -0.2794)
			(stroke
				(width 0.1)
				(type default)
			)
			(layer "F.Fab")
		)
		(fp_line
			(start -0.12065 -0.305054)
			(end -0.12065 -0.2794)
			(stroke
				(width 0.1)
				(type default)
			)
			(layer "F.Fab")
		)
		(fp_line
			(start -0.67945 0.3048)
			(end -0.67945 -0.305054)
			(stroke
				(width 0.1)
				(type default)
			)
			(layer "F.Fab")
		)
		(fp_line
			(start -0.67945 -0.305054)
			(end -0.12065 -0.305054)
			(stroke
				(width 0.1)
				(type default)
			)
			(layer "F.Fab")
		)
		(pad "1" smd rect
			(at -0.40005 0)
			(size 0.4572 0.508)
			(layers "F.Cu" "F.Mask" "F.Paste")
			(net "P1V8_CPU0_RT_1D")
		)
		(pad "2" smd rect
			(at 0.40005 0)
			(size 0.4572 0.508)
			(layers "F.Cu" "F.Mask" "F.Paste")
			(net "P1V8_CPU0_RT3_1A_1D")
		)
	)
	(footprint ""
		(layer "F.Cu")
		(at 140.385546 -75.19924 -90)
		(property "Reference" "PR6003"
			(at 0 0 270)
			(layer "F.SilkS")
			(hide yes)
			(effects
				(font
					(size 1.27 1.27)
				)
			)
		)
		(property "Value" ""
			(at 0 0 270)
			(layer "F.Fab")
			(effects
				(font
					(size 1.27 1.27)
				)
			)
		)
		(duplicate_pad_numbers_are_jumpers no)
		(fp_line
			(start -0.7874 0.4064)
			(end -0.7874 -0.4064)
			(stroke
				(width 0.1524)
				(type default)
			)
			(layer "F.SilkS")
		)
		(fp_line
			(start 0.7874 0.4064)
			(end -0.7874 0.4064)
			(stroke
				(width 0.1524)
				(type default)
			)
			(layer "F.SilkS")
		)
		(fp_line
			(start -0.7874 -0.4064)
			(end 0.7874 -0.4064)
			(stroke
				(width 0.1524)
				(type default)
			)
			(layer "F.SilkS")
		)
		(fp_line
			(start 0.7874 -0.4064)
			(end 0.7874 0.4064)
			(stroke
				(width 0.1524)
				(type default)
			)
			(layer "F.SilkS")
		)
		(fp_line
			(start -0.67945 0.3048)
			(end -0.67945 -0.305054)
			(stroke
				(width 0.1)
				(type default)
			)
			(layer "F.Fab")
		)
		(fp_line
			(start -0.12065 0.3048)
			(end -0.67945 0.3048)
			(stroke
				(width 0.1)
				(type default)
			)
			(layer "F.Fab")
		)
		(fp_line
			(start 0.120396 0.3048)
			(end 0.120396 0.2794)
			(stroke
				(width 0.1)
				(type default)
			)
			(layer "F.Fab")
		)
		(fp_line
			(start 0.67945 0.3048)
			(end 0.120396 0.3048)
			(stroke
				(width 0.1)
				(type default)
			)
			(layer "F.Fab")
		)
		(fp_line
			(start -0.12065 0.2794)
			(end -0.12065 0.3048)
			(stroke
				(width 0.1)
				(type default)
			)
			(layer "F.Fab")
		)
		(fp_line
			(start 0.120396 0.2794)
			(end -0.12065 0.2794)
			(stroke
				(width 0.1)
				(type default)
			)
			(layer "F.Fab")
		)
		(fp_line
			(start -0.12065 -0.2794)
			(end 0.12065 -0.2794)
			(stroke
				(width 0.1)
				(type default)
			)
			(layer "F.Fab")
		)
		(fp_line
			(start 0.12065 -0.2794)
			(end 0.12065 -0.3048)
			(stroke
				(width 0.1)
				(type default)
			)
			(layer "F.Fab")
		)
		(fp_line
			(start 0.12065 -0.3048)
			(end 0.67945 -0.3048)
			(stroke
				(width 0.1)
				(type default)
			)
			(layer "F.Fab")
		)
		(fp_line
			(start 0.67945 -0.3048)
			(end 0.67945 0.3048)
			(stroke
				(width 0.1)
				(type default)
			)
			(layer "F.Fab")
		)
		(fp_line
			(start -0.67945 -0.305054)
			(end -0.12065 -0.305054)
			(stroke
				(width 0.1)
				(type default)
			)
			(layer "F.Fab")
		)
		(fp_line
			(start -0.12065 -0.305054)
			(end -0.12065 -0.2794)
			(stroke
				(width 0.1)
				(type default)
			)
			(layer "F.Fab")
		)
		(pad "1" smd circle
			(at -0.40005 0 270)
			(size 0 0)
			(layers "F.Cu" "F.Mask" "F.Paste")
			(net "P1V8_AUX_CS")
		)
		(pad "2" smd circle
			(at 0.40005 0 270)
			(size 0 0)
			(layers "F.Cu" "F.Mask" "F.Paste")
			(net "GND")
		)
	)
)
